# T6G (Grand Teton) — schematic netlist excerpt (pin names and nets, part order shuffled) for the footprints in the layout excerpt that follows; sources: Cadence DE-HDL packaged netlist, KiCad conversion of 04192023_DAF0TMB3IC0_F0TG_MB_C_brd_V02_OCP.brd

R4149  Q_RES  33.2 1% CHIP  pkg 0402LF  page 151 : A = SMB_1_PLD_3V3AUX_SCL ; B = SMB_1_PLD_3V3AUX_SCL_R1
C3933  Q_CAP  22UF 4V 20% X6S  pkg C0402  page 70 : A = PVDD11_S3_P0 ; B = GND
PC6508  Q_CAP  22UF 4V 20% X6S  pkg C0805  page 360 : A = P1V8_CPU0_RT_1D ; B = GND

(kicad_pcb
	(version 20260206)
	(generator "pcbnew")
	(generator_version "10.0")
	(general
		(thickness 1.6)
		(legacy_teardrops no)
	)
	(paper "A4")
	(title_block
		(title "04192023_DAF0TMB3IC0_F0TG_MB_C_brd_V02_OCP.brd")
		(comment 1 "Grand Teton / footprints 6249-6251 of 8354")
	)
	(layers
		(0 "F.Cu" signal "TOP")
		(4 "In1.Cu" signal "GND")
		(6 "In2.Cu" signal "IN1")
		(8 "In3.Cu" signal "GND1")
		(10 "In4.Cu" signal "IN2")
		(12 "In5.Cu" signal "GND2")
		(14 "In6.Cu" signal "IN3")
		(16 "In7.Cu" signal "GND3")
		(18 "In8.Cu" signal "VCC")
		(20 "In9.Cu" signal "VCC1")
		(22 "In10.Cu" signal "GND4")
		(24 "In11.Cu" signal "IN4")
		(26 "In12.Cu" signal "GND5")
		(28 "In13.Cu" signal "IN5")
		(30 "In14.Cu" signal "GND6")
		(32 "In15.Cu" signal "IN6")
		(34 "In16.Cu" signal "GND7")
		(2 "B.Cu" signal "BOTTOM")
		(9 "F.Adhes" user "F.Adhesive")
		(11 "B.Adhes" user "B.Adhesive")
		(13 "F.Paste" user "Package Geometry/Pastemask Top")
		(15 "B.Paste" user "Package Geometry/Pastemask Bottom")
		(5 "F.SilkS" user "Ref Des/Silkscreen Top")
		(7 "B.SilkS" user "Ref Des/Silkscreen Bottom")
		(1 "F.Mask" user "Board Geometry/Soldermask Top")
		(3 "B.Mask" user "Board Geometry/Soldermask Bottom")
		(17 "Dwgs.User" user "User.Drawings")
		(19 "Cmts.User" user "User.Comments")
		(21 "Eco1.User" user "User.Eco1")
		(23 "Eco2.User" user "User.Eco2")
		(25 "Edge.Cuts" user "Board Geometry/Outline")
		(27 "Margin" user)
		(31 "F.CrtYd" user "Package Geometry/Place Bound Top")
		(29 "B.CrtYd" user "Package Geometry/Place Bound Bottom")
		(35 "F.Fab" user "Ref Des/Assembly Top")
		(33 "B.Fab" user "Ref Des/Assembly Bottom")
	)
	(footprint ""
		(layer "B.Cu")
		(at 162.46983 -17.79016 180)
		(property "Reference" "R4149"
			(at 0 0 0)
			(layer "B.SilkS")
			(hide yes)
			(effects
				(font
					(size 1.27 1.27)
				)
				(justify mirror)
			)
		)
		(property "Value" ""
			(at 0 0 0)
			(layer "B.Fab")
			(effects
				(font
					(size 1.27 1.27)
				)
				(justify mirror)
			)
		)
		(duplicate_pad_numbers_are_jumpers no)
		(fp_line
			(start 0.7874 0.4064)
			(end 0.7874 -0.4064)
			(stroke
				(width 0.1524)
				(type default)
			)
			(layer "B.SilkS")
		)
		(fp_line
			(start 0.7874 -0.4064)
			(end -0.7874 -0.4064)
			(stroke
				(width 0.1524)
				(type default)
			)
			(layer "B.SilkS")
		)
		(fp_line
			(start -0.7874 0.4064)
			(end 0.7874 0.4064)
			(stroke
				(width 0.1524)
				(type default)
			)
			(layer "B.SilkS")
		)
		(fp_line
			(start -0.7874 -0.4064)
			(end -0.7874 0.4064)
			(stroke
				(width 0.1524)
				(type default)
			)
			(layer "B.SilkS")
		)
		(fp_line
			(start 0.67945 0.3048)
			(end 0.67945 -0.305054)
			(stroke
				(width 0.1)
				(type default)
			)
			(layer "B.Fab")
		)
		(fp_line
			(start 0.67945 -0.305054)
			(end 0.12065 -0.305054)
			(stroke
				(width 0.1)
				(type default)
			)
			(layer "B.Fab")
		)
		(fp_line
			(start 0.12065 0.3048)
			(end 0.67945 0.3048)
			(stroke
				(width 0.1)
				(type default)
			)
			(layer "B.Fab")
		)
		(fp_line
			(start 0.12065 0.2794)
			(end 0.12065 0.3048)
			(stroke
				(width 0.1)
				(type default)
			)
			(layer "B.Fab")
		)
		(fp_line
			(start 0.12065 -0.2794)
			(end -0.12065 -0.2794)
			(stroke
				(width 0.1)
				(type default)
			)
			(layer "B.Fab")
		)
		(fp_line
			(start 0.12065 -0.305054)
			(end 0.12065 -0.2794)
			(stroke
				(width 0.1)
				(type default)
			)
			(layer "B.Fab")
		)
		(fp_line
			(start -0.120396 0.3048)
			(end -0.120396 0.2794)
			(stroke
				(width 0.1)
				(type default)
			)
			(layer "B.Fab")
		)
		(fp_line
			(start -0.120396 0.2794)
			(end 0.12065 0.2794)
			(stroke
				(width 0.1)
				(type default)
			)
			(layer "B.Fab")
		)
		(fp_line
			(start -0.12065 -0.2794)
			(end -0.12065 -0.3048)
			(stroke
				(width 0.1)
				(type default)
			)
			(layer "B.Fab")
		)
		(fp_line
			(start -0.12065 -0.3048)
			(end -0.67945 -0.3048)
			(stroke
				(width 0.1)
				(type default)
			)
			(layer "B.Fab")
		)
		(fp_line
			(start -0.67945 0.3048)
			(end -0.120396 0.3048)
			(stroke
				(width 0.1)
				(type default)
			)
			(layer "B.Fab")
		)
		(fp_line
			(start -0.67945 -0.3048)
			(end -0.67945 0.3048)
			(stroke
				(width 0.1)
				(type default)
			)
			(layer "B.Fab")
		)
		(pad "1" smd circle
			(at 0.40005 0)
			(size 0 0)
			(layers "B.Cu" "B.Mask" "B.Paste")
			(net "SMB_1_PLD_3V3AUX_SCL")
		)
		(pad "2" smd circle
			(at -0.40005 0)
			(size 0 0)
			(layers "B.Cu" "B.Mask" "B.Paste")
			(net "SMB_1_PLD_3V3AUX_SCL_R1")
		)
	)
	(footprint ""
		(layer "B.Cu")
		(at 352.501454 -266.00531)
		(property "Reference" "C3933"
			(at 0 0 0)
			(layer "B.SilkS")
			(hide yes)
			(effects
				(font
					(size 1.27 1.27)
				)
				(justify mirror)
			)
		)
		(property "Value" ""
			(at 0 0 0)
			(layer "B.Fab")
			(effects
				(font
					(size 1.27 1.27)
				)
				(justify mirror)
			)
		)
		(duplicate_pad_numbers_are_jumpers no)
		(fp_line
			(start -0.7874 -0.4064)
			(end -0.7874 0.4064)
			(stroke
				(width 0.1524)
				(type default)
			)
			(layer "B.SilkS")
		)
		(fp_line
			(start -0.7874 0.4064)
			(end 0.7874 0.4064)
			(stroke
				(width 0.1524)
				(type default)
			)
			(layer "B.SilkS")
		)
		(fp_line
			(start 0.7874 -0.4064)
			(end -0.7874 -0.4064)
			(stroke
				(width 0.1524)
				(type default)
			)
			(layer "B.SilkS")
		)
		(fp_line
			(start 0.7874 0.4064)
			(end 0.7874 -0.4064)
			(stroke
				(width 0.1524)
				(type default)
			)
			(layer "B.SilkS")
		)
		(fp_line
			(start -0.67945 -0.3048)
			(end -0.67945 0.3048)
			(stroke
				(width 0.1)
				(type default)
			)
			(layer "B.Fab")
		)
		(fp_line
			(start -0.67945 0.3048)
			(end -0.120396 0.3048)
			(stroke
				(width 0.1)
				(type default)
			)
			(layer "B.Fab")
		)
		(fp_line
			(start -0.12065 -0.3048)
			(end -0.67945 -0.3048)
			(stroke
				(width 0.1)
				(type default)
			)
			(layer "B.Fab")
		)
		(fp_line
			(start -0.12065 -0.2794)
			(end -0.12065 -0.3048)
			(stroke
				(width 0.1)
				(type default)
			)
			(layer "B.Fab")
		)
		(fp_line
			(start -0.120396 0.2794)
			(end 0.12065 0.2794)
			(stroke
				(width 0.1)
				(type default)
			)
			(layer "B.Fab")
		)
		(fp_line
			(start -0.120396 0.3048)
			(end -0.120396 0.2794)
			(stroke
				(width 0.1)
				(type default)
			)
			(layer "B.Fab")
		)
		(fp_line
			(start 0.12065 -0.305054)
			(end 0.12065 -0.2794)
			(stroke
				(width 0.1)
				(type default)
			)
			(layer "B.Fab")
		)
		(fp_line
			(start 0.12065 -0.2794)
			(end -0.12065 -0.2794)
			(stroke
				(width 0.1)
				(type default)
			)
			(layer "B.Fab")
		)
		(fp_line
			(start 0.12065 0.2794)
			(end 0.12065 0.3048)
			(stroke
				(width 0.1)
				(type default)
			)
			(layer "B.Fab")
		)
		(fp_line
			(start 0.12065 0.3048)
			(end 0.67945 0.3048)
			(stroke
				(width 0.1)
				(type default)
			)
			(layer "B.Fab")
		)
		(fp_line
			(start 0.67945 -0.305054)
			(end 0.12065 -0.305054)
			(stroke
				(width 0.1)
				(type default)
			)
			(layer "B.Fab")
		)
		(fp_line
			(start 0.67945 0.3048)
			(end 0.67945 -0.305054)
			(stroke
				(width 0.1)
				(type default)
			)
			(layer "B.Fab")
		)
		(pad "1" smd circle
			(at 0.40005 0 180)
			(size 0 0)
			(layers "B.Cu" "B.Mask" "B.Paste")
			(net "PVDD11_S3_P0")
		)
		(pad "2" smd circle
			(at -0.40005 0 180)
			(size 0 0)
			(layers "B.Cu" "B.Mask" "B.Paste")
			(net "GND")
		)
	)
	(footprint ""
		(layer "B.Cu")
		(at 243.816378 -315.95568 -90)
		(property "Reference" "PC6508"
			(at 0 0 90)
			(layer "B.SilkS")
			(hide yes)
			(effects
				(font
					(size 1.27 1.27)
				)
				(justify mirror)
			)
		)
		(property "Value" ""
			(at 0 0 90)
			(layer "B.Fab")
			(effects
				(font
					(size 1.27 1.27)
				)
				(justify mirror)
			)
		)
		(duplicate_pad_numbers_are_jumpers no)
		(fp_line
			(start -1.524 0.762)
			(end 1.524 0.762)
			(stroke
				(width 0.1524)
				(type default)
			)
			(layer "B.SilkS")
		)
		(fp_line
			(start 1.524 0.762)
			(end 1.524 -0.762)
			(stroke
				(width 0.1524)
				(type default)
			)
			(layer "B.SilkS")
		)
		(fp_line
			(start -1.524 -0.762)
			(end -1.524 0.762)
			(stroke
				(width 0.1524)
				(type default)
			)
			(layer "B.SilkS")
		)
		(fp_line
			(start 1.524 -0.762)
			(end -1.524 -0.762)
			(stroke
				(width 0.1524)
				(type default)
			)
			(layer "B.SilkS")
		)
		(fp_line
			(start -1.1049 0.724916)
			(end -1.1049 -0.724916)
			(stroke
				(width 0.1)
				(type default)
			)
			(layer "B.Fab")
		)
		(fp_line
			(start 1.1049 0.724916)
			(end -1.1049 0.724916)
			(stroke
				(width 0.1)
				(type default)
			)
			(layer "B.Fab")
		)
		(fp_line
			(start -1.1049 -0.724916)
			(end 1.1049 -0.724916)
			(stroke
				(width 0.1)
				(type default)
			)
			(layer "B.Fab")
		)
		(fp_line
			(start 1.1049 -0.724916)
			(end 1.1049 0.724916)
			(stroke
				(width 0.1)
				(type default)
			)
			(layer "B.Fab")
		)
		(pad "1" smd rect
			(at 0.889 0 270)
			(size 1.016 1.27)
			(layers "B.Cu" "B.Mask" "B.Paste")
			(net "P1V8_CPU0_RT_1D")
		)
		(pad "2" smd rect
			(at -0.889 0 270)
			(size 1.016 1.27)
			(layers "B.Cu" "B.Mask" "B.Paste")
			(net "GND")
		)
	)
)
